(kicad_pcb
	(version 20260206)
	(generator "pcbnew")
	(generator_version "10.0")
	(general
		(thickness 1.6)
		(legacy_teardrops no)
	)
	(paper "A4")
	(title_block
		(title "03242023_DA0F0TMBIJ0_F0T_Motherboard_J_brd_V01_OCP.brd")
		(comment 1 "Grand Teton / footprints 502-507 of 6105")
	)
	(layers
		(0 "F.Cu" signal "TOP")
		(4 "In1.Cu" signal "GND")
		(6 "In2.Cu" signal "IN1")
		(8 "In3.Cu" signal "GND1")
		(10 "In4.Cu" signal "IN2")
		(12 "In5.Cu" signal "GND2")
		(14 "In6.Cu" signal "IN3")
		(16 "In7.Cu" signal "GND3")
		(18 "In8.Cu" signal "VCC")
		(20 "In9.Cu" signal "VCC1")
		(22 "In10.Cu" signal "GND4")
		(24 "In11.Cu" signal "IN4")
		(26 "In12.Cu" signal "GND5")
		(28 "In13.Cu" signal "IN5")
		(30 "In14.Cu" signal "GND6")
		(32 "In15.Cu" signal "IN6")
		(34 "In16.Cu" signal "GND7")
		(2 "B.Cu" signal "BOTTOM")
		(9 "F.Adhes" user "F.Adhesive")
		(11 "B.Adhes" user "B.Adhesive")
		(13 "F.Paste" user "Package Geometry/Pastemask Top")
		(15 "B.Paste" user "Package Geometry/Pastemask Bottom")
		(5 "F.SilkS" user "Ref Des/Silkscreen Top")
		(7 "B.SilkS" user "Ref Des/Silkscreen Bottom")
		(1 "F.Mask" user "Board Geometry/Soldermask Top")
		(3 "B.Mask" user "Board Geometry/Soldermask Bottom")
		(17 "Dwgs.User" user "User.Drawings")
		(19 "Cmts.User" user "User.Comments")
		(21 "Eco1.User" user "User.Eco1")
		(23 "Eco2.User" user "User.Eco2")
		(25 "Edge.Cuts" user "Board Geometry/Outline")
		(27 "Margin" user)
		(31 "F.CrtYd" user "Package Geometry/Place Bound Top")
		(29 "B.CrtYd" user "Package Geometry/Place Bound Bottom")
		(35 "F.Fab" user "Ref Des/Assembly Top")
		(33 "B.Fab" user "Ref Des/Assembly Bottom")
	)
	(footprint ""
		(layer "F.Cu")
		(at 453.719946 -102.598728)
		(property "Reference" "R1908"
			(at 0 0 0)
			(layer "F.SilkS")
			(hide yes)
			(effects
				(font
					(size 1.27 1.27)
				)
			)
		)
		(property "Value" ""
			(at 0 0 0)
			(layer "F.Fab")
			(effects
				(font
					(size 1.27 1.27)
				)
			)
		)
		(duplicate_pad_numbers_are_jumpers no)
		(fp_line
			(start -0.7874 -0.4064)
			(end 0.7874 -0.4064)
			(stroke
				(width 0.1524)
				(type default)
			)
			(layer "F.SilkS")
		)
		(fp_line
			(start -0.7874 0.4064)
			(end -0.7874 -0.4064)
			(stroke
				(width 0.1524)
				(type default)
			)
			(layer "F.SilkS")
		)
		(fp_line
			(start 0.7874 -0.4064)
			(end 0.7874 0.4064)
			(stroke
				(width 0.1524)
				(type default)
			)
			(layer "F.SilkS")
		)
		(fp_line
			(start 0.7874 0.4064)
			(end -0.7874 0.4064)
			(stroke
				(width 0.1524)
				(type default)
			)
			(layer "F.SilkS")
		)
		(fp_line
			(start -0.67945 -0.305054)
			(end -0.12065 -0.305054)
			(stroke
				(width 0.1)
				(type default)
			)
			(layer "F.Fab")
		)
		(fp_line
			(start -0.67945 0.3048)
			(end -0.67945 -0.305054)
			(stroke
				(width 0.1)
				(type default)
			)
			(layer "F.Fab")
		)
		(fp_line
			(start -0.12065 -0.305054)
			(end -0.12065 -0.2794)
			(stroke
				(width 0.1)
				(type default)
			)
			(layer "F.Fab")
		)
		(fp_line
			(start -0.12065 -0.2794)
			(end 0.12065 -0.2794)
			(stroke
				(width 0.1)
				(type default)
			)
			(layer "F.Fab")
		)
		(fp_line
			(start -0.12065 0.2794)
			(end -0.12065 0.3048)
			(stroke
				(width 0.1)
				(type default)
			)
			(layer "F.Fab")
		)
		(fp_line
			(start -0.12065 0.3048)
			(end -0.67945 0.3048)
			(stroke
				(width 0.1)
				(type default)
			)
			(layer "F.Fab")
		)
		(fp_line
			(start 0.120396 0.2794)
			(end -0.12065 0.2794)
			(stroke
				(width 0.1)
				(type default)
			)
			(layer "F.Fab")
		)
		(fp_line
			(start 0.120396 0.3048)
			(end 0.120396 0.2794)
			(stroke
				(width 0.1)
				(type default)
			)
			(layer "F.Fab")
		)
		(fp_line
			(start 0.12065 -0.3048)
			(end 0.67945 -0.3048)
			(stroke
				(width 0.1)
				(type default)
			)
			(layer "F.Fab")
		)
		(fp_line
			(start 0.12065 -0.2794)
			(end 0.12065 -0.3048)
			(stroke
				(width 0.1)
				(type default)
			)
			(layer "F.Fab")
		)
		(fp_line
			(start 0.67945 -0.3048)
			(end 0.67945 0.3048)
			(stroke
				(width 0.1)
				(type default)
			)
			(layer "F.Fab")
		)
		(fp_line
			(start 0.67945 0.3048)
			(end 0.120396 0.3048)
			(stroke
				(width 0.1)
				(type default)
			)
			(layer "F.Fab")
		)
		(pad "1" smd circle
			(at -0.40005 0)
			(size 0 0)
			(layers "F.Cu" "F.Mask" "F.Paste")
			(net "P3V3_AUX")
		)
		(pad "2" smd circle
			(at 0.40005 0)
			(size 0 0)
			(layers "F.Cu" "F.Mask" "F.Paste")
			(net "OCP_SFF_PRSNT3_R_N")
		)
	)
	(footprint ""
		(layer "F.Cu")
		(at 40.627554 -111.606838 180)
		(property "Reference" "R3865"
			(at 0 0 180)
			(layer "F.SilkS")
			(hide yes)
			(effects
				(font
					(size 1.27 1.27)
				)
			)
		)
		(property "Value" ""
			(at 0 0 180)
			(layer "F.Fab")
			(effects
				(font
					(size 1.27 1.27)
				)
			)
		)
		(duplicate_pad_numbers_are_jumpers no)
		(fp_line
			(start 0.7874 0.4064)
			(end -0.7874 0.4064)
			(stroke
				(width 0.1524)
				(type default)
			)
			(layer "F.SilkS")
		)
		(fp_line
			(start 0.7874 -0.4064)
			(end 0.7874 0.4064)
			(stroke
				(width 0.1524)
				(type default)
			)
			(layer "F.SilkS")
		)
		(fp_line
			(start -0.7874 0.4064)
			(end -0.7874 -0.4064)
			(stroke
				(width 0.1524)
				(type default)
			)
			(layer "F.SilkS")
		)
		(fp_line
			(start -0.7874 -0.4064)
			(end 0.7874 -0.4064)
			(stroke
				(width 0.1524)
				(type default)
			)
			(layer "F.SilkS")
		)
		(fp_line
			(start 0.67945 0.3048)
			(end 0.120396 0.3048)
			(stroke
				(width 0.1)
				(type default)
			)
			(layer "F.Fab")
		)
		(fp_line
			(start 0.67945 -0.3048)
			(end 0.67945 0.3048)
			(stroke
				(width 0.1)
				(type default)
			)
			(layer "F.Fab")
		)
		(fp_line
			(start 0.12065 -0.2794)
			(end 0.12065 -0.3048)
			(stroke
				(width 0.1)
				(type default)
			)
			(layer "F.Fab")
		)
		(fp_line
			(start 0.12065 -0.3048)
			(end 0.67945 -0.3048)
			(stroke
				(width 0.1)
				(type default)
			)
			(layer "F.Fab")
		)
		(fp_line
			(start 0.120396 0.3048)
			(end 0.120396 0.2794)
			(stroke
				(width 0.1)
				(type default)
			)
			(layer "F.Fab")
		)
		(fp_line
			(start 0.120396 0.2794)
			(end -0.12065 0.2794)
			(stroke
				(width 0.1)
				(type default)
			)
			(layer "F.Fab")
		)
		(fp_line
			(start -0.12065 0.3048)
			(end -0.67945 0.3048)
			(stroke
				(width 0.1)
				(type default)
			)
			(layer "F.Fab")
		)
		(fp_line
			(start -0.12065 0.2794)
			(end -0.12065 0.3048)
			(stroke
				(width 0.1)
				(type default)
			)
			(layer "F.Fab")
		)
		(fp_line
			(start -0.12065 -0.2794)
			(end 0.12065 -0.2794)
			(stroke
				(width 0.1)
				(type default)
			)
			(layer "F.Fab")
		)
		(fp_line
			(start -0.12065 -0.305054)
			(end -0.12065 -0.2794)
			(stroke
				(width 0.1)
				(type default)
			)
			(layer "F.Fab")
		)
		(fp_line
			(start -0.67945 0.3048)
			(end -0.67945 -0.305054)
			(stroke
				(width 0.1)
				(type default)
			)
			(layer "F.Fab")
		)
		(fp_line
			(start -0.67945 -0.305054)
			(end -0.12065 -0.305054)
			(stroke
				(width 0.1)
				(type default)
			)
			(layer "F.Fab")
		)
		(pad "1" smd rect
			(at -0.40005 0)
			(size 0.4572 0.508)
			(layers "F.Cu" "F.Mask" "F.Paste")
			(net "P12V_OCP_SFF_ISENSE_MAM_TIC")
		)
		(pad "2" smd rect
			(at 0.40005 0)
			(size 0.4572 0.508)
			(layers "F.Cu" "F.Mask" "F.Paste")
			(net "P12V_OCP_SFF_ISENSE_TIC")
		)
	)
	(footprint ""
		(layer "F.Cu")
		(at 213.93658 -127.782828 180)
		(property "Reference" "U95"
			(at -1.36144 -3.72491 0)
			(unlocked yes)
			(layer "F.SilkS")
			(effects
				(font
					(size 0.7874 0.5842)
					(thickness 0.1524)
				)
				(justify left)
			)
		)
		(property "Value" ""
			(at 0 0 180)
			(layer "F.Fab")
			(effects
				(font
					(size 1.27 1.27)
				)
			)
		)
		(duplicate_pad_numbers_are_jumpers no)
		(fp_line
			(start 1.400048 1.100074)
			(end -1.400048 1.100074)
			(stroke
				(width 0.1524)
				(type default)
			)
			(layer "F.SilkS")
		)
		(fp_line
			(start 1.400048 -1.100074)
			(end 1.400048 1.100074)
			(stroke
				(width 0.1524)
				(type default)
			)
			(layer "F.SilkS")
		)
		(fp_line
			(start 1.400048 -1.100074)
			(end -1.400048 -1.100074)
			(stroke
				(width 0.1524)
				(type default)
			)
			(layer "F.SilkS")
		)
		(fp_line
			(start -1.400048 1.100074)
			(end -1.400048 -1.100074)
			(stroke
				(width 0.1524)
				(type default)
			)
			(layer "F.SilkS")
		)
		(fp_poly
			(pts
				(xy -1.247394 -1.455928) (xy -1.755394 -2.471928) (xy -0.739394 -2.471928)
			)
			(stroke
				(width 0)
				(type default)
			)
			(fill yes)
			(layer "F.SilkS")
		)
		(fp_line
			(start 0.674878 1.100074)
			(end -0.674878 1.100074)
			(stroke
				(width 0.1)
				(type default)
			)
			(layer "F.Fab")
		)
		(fp_line
			(start 0.674878 -1.100074)
			(end 0.674878 1.100074)
			(stroke
				(width 0.1)
				(type default)
			)
			(layer "F.Fab")
		)
		(fp_line
			(start -0.674878 1.100074)
			(end -0.674878 -1.100074)
			(stroke
				(width 0.1)
				(type default)
			)
			(layer "F.Fab")
		)
		(fp_line
			(start -0.674878 -1.100074)
			(end 0.674878 -1.100074)
			(stroke
				(width 0.1)
				(type default)
			)
			(layer "F.Fab")
		)
		(fp_poly
			(pts
				(xy -1.590548 -0.649986) (xy -2.606548 -1.157986) (xy -2.606548 -0.141986)
			)
			(stroke
				(width 0)
				(type default)
			)
			(fill yes)
			(layer "F.Fab")
		)
		(pad "1" smd rect
			(at -0.94996 -0.649986 90)
			(size 0.4318 0.6096)
			(layers "F.Cu" "F.Mask" "F.Paste")
			(net "Net_1913")
		)
		(pad "2" smd rect
			(at -0.94996 0 90)
			(size 0.4318 0.6096)
			(layers "F.Cu" "F.Mask" "F.Paste")
			(net "PWRGD_DSW_PWROK_R1")
		)
		(pad "3" smd rect
			(at -0.94996 0.649986 90)
			(size 0.4318 0.6096)
			(layers "F.Cu" "F.Mask" "F.Paste")
			(net "GND")
		)
		(pad "4" smd rect
			(at 0.94996 0.649986 90)
			(size 0.4318 0.6096)
			(layers "F.Cu" "F.Mask" "F.Paste")
			(net "PWRGD_DSW_PWROK_R2")
		)
		(pad "5" smd rect
			(at 0.94996 -0.649986 90)
			(size 0.4318 0.6096)
			(layers "F.Cu" "F.Mask" "F.Paste")
			(net "P3V3_AUX")
		)
	)
	(footprint ""
		(layer "F.Cu")
		(at 102.845616 -356.668578)
		(property "Reference" "R311"
			(at 0 0 0)
			(layer "F.SilkS")
			(hide yes)
			(effects
				(font
					(size 1.27 1.27)
				)
			)
		)
		(property "Value" ""
			(at 0 0 0)
			(layer "F.Fab")
			(effects
				(font
					(size 1.27 1.27)
				)
			)
		)
		(duplicate_pad_numbers_are_jumpers no)
		(fp_line
			(start -0.7874 -0.4064)
			(end 0.7874 -0.4064)
			(stroke
				(width 0.1524)
				(type default)
			)
			(layer "F.SilkS")
		)
		(fp_line
			(start -0.7874 0.4064)
			(end -0.7874 -0.4064)
			(stroke
				(width 0.1524)
				(type default)
			)
			(layer "F.SilkS")
		)
		(fp_line
			(start 0.7874 -0.4064)
			(end 0.7874 0.4064)
			(stroke
				(width 0.1524)
				(type default)
			)
			(layer "F.SilkS")
		)
		(fp_line
			(start 0.7874 0.4064)
			(end -0.7874 0.4064)
			(stroke
				(width 0.1524)
				(type default)
			)
			(layer "F.SilkS")
		)
		(fp_line
			(start -0.67945 -0.305054)
			(end -0.12065 -0.305054)
			(stroke
				(width 0.1)
				(type default)
			)
			(layer "F.Fab")
		)
		(fp_line
			(start -0.67945 0.3048)
			(end -0.67945 -0.305054)
			(stroke
				(width 0.1)
				(type default)
			)
			(layer "F.Fab")
		)
		(fp_line
			(start -0.12065 -0.305054)
			(end -0.12065 -0.2794)
			(stroke
				(width 0.1)
				(type default)
			)
			(layer "F.Fab")
		)
		(fp_line
			(start -0.12065 -0.2794)
			(end 0.12065 -0.2794)
			(stroke
				(width 0.1)
				(type default)
			)
			(layer "F.Fab")
		)
		(fp_line
			(start -0.12065 0.2794)
			(end -0.12065 0.3048)
			(stroke
				(width 0.1)
				(type default)
			)
			(layer "F.Fab")
		)
		(fp_line
			(start -0.12065 0.3048)
			(end -0.67945 0.3048)
			(stroke
				(width 0.1)
				(type default)
			)
			(layer "F.Fab")
		)
		(fp_line
			(start 0.120396 0.2794)
			(end -0.12065 0.2794)
			(stroke
				(width 0.1)
				(type default)
			)
			(layer "F.Fab")
		)
		(fp_line
			(start 0.120396 0.3048)
			(end 0.120396 0.2794)
			(stroke
				(width 0.1)
				(type default)
			)
			(layer "F.Fab")
		)
		(fp_line
			(start 0.12065 -0.3048)
			(end 0.67945 -0.3048)
			(stroke
				(width 0.1)
				(type default)
			)
			(layer "F.Fab")
		)
		(fp_line
			(start 0.12065 -0.2794)
			(end 0.12065 -0.3048)
			(stroke
				(width 0.1)
				(type default)
			)
			(layer "F.Fab")
		)
		(fp_line
			(start 0.67945 -0.3048)
			(end 0.67945 0.3048)
			(stroke
				(width 0.1)
				(type default)
			)
			(layer "F.Fab")
		)
		(fp_line
			(start 0.67945 0.3048)
			(end 0.120396 0.3048)
			(stroke
				(width 0.1)
				(type default)
			)
			(layer "F.Fab")
		)
		(pad "1" smd circle
			(at -0.40005 0)
			(size 0 0)
			(layers "F.Cu" "F.Mask" "F.Paste")
			(net "SVID_DIO0_CPU1_R")
		)
		(pad "2" smd circle
			(at 0.40005 0)
			(size 0 0)
			(layers "F.Cu" "F.Mask" "F.Paste")
			(net "SVID_DIO_PVCCIN_CPU1_R")
		)
	)
	(footprint ""
		(layer "F.Cu")
		(at 302.85436 -430.65827 -90)
		(property "Reference" "R4132"
			(at 0 0 270)
			(layer "F.SilkS")
			(hide yes)
			(effects
				(font
					(size 1.27 1.27)
				)
			)
		)
		(property "Value" ""
			(at 0 0 270)
			(layer "F.Fab")
			(effects
				(font
					(size 1.27 1.27)
				)
			)
		)
		(duplicate_pad_numbers_are_jumpers no)
		(fp_line
			(start -0.7874 0.4064)
			(end -0.7874 -0.4064)
			(stroke
				(width 0.1524)
				(type default)
			)
			(layer "F.SilkS")
		)
		(fp_line
			(start 0.7874 0.4064)
			(end -0.7874 0.4064)
			(stroke
				(width 0.1524)
				(type default)
			)
			(layer "F.SilkS")
		)
		(fp_line
			(start -0.7874 -0.4064)
			(end 0.7874 -0.4064)
			(stroke
				(width 0.1524)
				(type default)
			)
			(layer "F.SilkS")
		)
		(fp_line
			(start 0.7874 -0.4064)
			(end 0.7874 0.4064)
			(stroke
				(width 0.1524)
				(type default)
			)
			(layer "F.SilkS")
		)
		(fp_line
			(start -0.67945 0.3048)
			(end -0.67945 -0.305054)
			(stroke
				(width 0.1)
				(type default)
			)
			(layer "F.Fab")
		)
		(fp_line
			(start -0.12065 0.3048)
			(end -0.67945 0.3048)
			(stroke
				(width 0.1)
				(type default)
			)
			(layer "F.Fab")
		)
		(fp_line
			(start 0.120396 0.3048)
			(end 0.120396 0.2794)
			(stroke
				(width 0.1)
				(type default)
			)
			(layer "F.Fab")
		)
		(fp_line
			(start 0.67945 0.3048)
			(end 0.120396 0.3048)
			(stroke
				(width 0.1)
				(type default)
			)
			(layer "F.Fab")
		)
		(fp_line
			(start -0.12065 0.2794)
			(end -0.12065 0.3048)
			(stroke
				(width 0.1)
				(type default)
			)
			(layer "F.Fab")
		)
		(fp_line
			(start 0.120396 0.2794)
			(end -0.12065 0.2794)
			(stroke
				(width 0.1)
				(type default)
			)
			(layer "F.Fab")
		)
		(fp_line
			(start -0.12065 -0.2794)
			(end 0.12065 -0.2794)
			(stroke
				(width 0.1)
				(type default)
			)
			(layer "F.Fab")
		)
		(fp_line
			(start 0.12065 -0.2794)
			(end 0.12065 -0.3048)
			(stroke
				(width 0.1)
				(type default)
			)
			(layer "F.Fab")
		)
		(fp_line
			(start 0.12065 -0.3048)
			(end 0.67945 -0.3048)
			(stroke
				(width 0.1)
				(type default)
			)
			(layer "F.Fab")
		)
		(fp_line
			(start 0.67945 -0.3048)
			(end 0.67945 0.3048)
			(stroke
				(width 0.1)
				(type default)
			)
			(layer "F.Fab")
		)
		(fp_line
			(start -0.67945 -0.305054)
			(end -0.12065 -0.305054)
			(stroke
				(width 0.1)
				(type default)
			)
			(layer "F.Fab")
		)
		(fp_line
			(start -0.12065 -0.305054)
			(end -0.12065 -0.2794)
			(stroke
				(width 0.1)
				(type default)
			)
			(layer "F.Fab")
		)
		(pad "1" smd circle
			(at -0.40005 0 270)
			(size 0 0)
			(layers "F.Cu" "F.Mask" "F.Paste")
			(net "GPU_3V3IO_RSVD3_FFU")
		)
		(pad "2" smd circle
			(at 0.40005 0 270)
			(size 0 0)
			(layers "F.Cu" "F.Mask" "F.Paste")
			(net "GND")
		)
	)
	(footprint ""
		(layer "F.Cu")
		(at 187.50788 -99.659948 -90)
		(property "Reference" "R188"
			(at 0 0 270)
			(layer "F.SilkS")
			(hide yes)
			(effects
				(font
					(size 1.27 1.27)
				)
			)
		)
		(property "Value" ""
			(at 0 0 270)
			(layer "F.Fab")
			(effects
				(font
					(size 1.27 1.27)
				)
			)
		)
		(duplicate_pad_numbers_are_jumpers no)
		(fp_line
			(start -0.7874 0.4064)
			(end -0.7874 -0.4064)
			(stroke
				(width 0.1524)
				(type default)
			)
			(layer "F.SilkS")
		)
		(fp_line
			(start 0.7874 0.4064)
			(end -0.7874 0.4064)
			(stroke
				(width 0.1524)
				(type default)
			)
			(layer "F.SilkS")
		)
		(fp_line
			(start -0.7874 -0.4064)
			(end 0.7874 -0.4064)
			(stroke
				(width 0.1524)
				(type default)
			)
			(layer "F.SilkS")
		)
		(fp_line
			(start 0.7874 -0.4064)
			(end 0.7874 0.4064)
			(stroke
				(width 0.1524)
				(type default)
			)
			(layer "F.SilkS")
		)
		(fp_line
			(start -0.67945 0.3048)
			(end -0.67945 -0.305054)
			(stroke
				(width 0.1)
				(type default)
			)
			(layer "F.Fab")
		)
		(fp_line
			(start -0.12065 0.3048)
			(end -0.67945 0.3048)
			(stroke
				(width 0.1)
				(type default)
			)
			(layer "F.Fab")
		)
		(fp_line
			(start 0.120396 0.3048)
			(end 0.120396 0.2794)
			(stroke
				(width 0.1)
				(type default)
			)
			(layer "F.Fab")
		)
		(fp_line
			(start 0.67945 0.3048)
			(end 0.120396 0.3048)
			(stroke
				(width 0.1)
				(type default)
			)
			(layer "F.Fab")
		)
		(fp_line
			(start -0.12065 0.2794)
			(end -0.12065 0.3048)
			(stroke
				(width 0.1)
				(type default)
			)
			(layer "F.Fab")
		)
		(fp_line
			(start 0.120396 0.2794)
			(end -0.12065 0.2794)
			(stroke
				(width 0.1)
				(type default)
			)
			(layer "F.Fab")
		)
		(fp_line
			(start -0.12065 -0.2794)
			(end 0.12065 -0.2794)
			(stroke
				(width 0.1)
				(type default)
			)
			(layer "F.Fab")
		)
		(fp_line
			(start 0.12065 -0.2794)
			(end 0.12065 -0.3048)
			(stroke
				(width 0.1)
				(type default)
			)
			(layer "F.Fab")
		)
		(fp_line
			(start 0.12065 -0.3048)
			(end 0.67945 -0.3048)
			(stroke
				(width 0.1)
				(type default)
			)
			(layer "F.Fab")
		)
		(fp_line
			(start 0.67945 -0.3048)
			(end 0.67945 0.3048)
			(stroke
				(width 0.1)
				(type default)
			)
			(layer "F.Fab")
		)
		(fp_line
			(start -0.67945 -0.305054)
			(end -0.12065 -0.305054)
			(stroke
				(width 0.1)
				(type default)
			)
			(layer "F.Fab")
		)
		(fp_line
			(start -0.12065 -0.305054)
			(end -0.12065 -0.2794)
			(stroke
				(width 0.1)
				(type default)
			)
			(layer "F.Fab")
		)
		(pad "1" smd circle
			(at -0.40005 0 270)
			(size 0 0)
			(layers "F.Cu" "F.Mask" "F.Paste")
			(net "H_CPU_NMI_LVC1_R_N")
		)
		(pad "2" smd circle
			(at 0.40005 0 270)
			(size 0 0)
			(layers "F.Cu" "F.Mask" "F.Paste")
			(net "H_CPU_NMI_LVC1_N")
		)
	)
)
